(kicad_pcb
	(version 20260206)
	(generator "pcbnew")
	(generator_version "10.0")
	(general
		(thickness 1.6)
		(legacy_teardrops no)
	)
	(paper "A4")
	(title_block
		(title "panther-plus-userver — 13130-1b_20150205.brd")
		(comment 1 "Honey Badger (Wiwynn) / footprints 1282-1289 of 1509")
	)
	(layers
		(0 "F.Cu" signal "TOP")
		(4 "In1.Cu" signal "L2")
		(6 "In2.Cu" signal "L3")
		(8 "In3.Cu" signal "L4")
		(10 "In4.Cu" signal "L5")
		(12 "In5.Cu" signal "L6")
		(14 "In6.Cu" signal "L7")
		(16 "In7.Cu" signal "L8")
		(18 "In8.Cu" signal "L9")
		(20 "In9.Cu" signal "L10")
		(22 "In10.Cu" signal "L11")
		(2 "B.Cu" signal "BOTTOM")
		(9 "F.Adhes" user "F.Adhesive")
		(11 "B.Adhes" user "B.Adhesive")
		(13 "F.Paste" user "Package Geometry/Pastemask Top")
		(15 "B.Paste" user "Package Geometry/Pastemask Bottom")
		(5 "F.SilkS" user "Ref Des/Silkscreen Top")
		(7 "B.SilkS" user "Ref Des/Silkscreen Bottom")
		(1 "F.Mask" user "Board Geometry/Soldermask Top")
		(3 "B.Mask" user "Board Geometry/Soldermask Bottom")
		(17 "Dwgs.User" user "User.Drawings")
		(19 "Cmts.User" user "User.Comments")
		(21 "Eco1.User" user "User.Eco1")
		(23 "Eco2.User" user "User.Eco2")
		(25 "Edge.Cuts" user "Board Geometry/Outline")
		(27 "Margin" user)
		(31 "F.CrtYd" user "Package Geometry/Place Bound Top")
		(29 "B.CrtYd" user "Package Geometry/Place Bound Bottom")
		(35 "F.Fab" user "Ref Des/Assembly Top")
		(33 "B.Fab" user "Ref Des/Assembly Bottom")
	)
	(footprint ""
		(layer "B.Cu")
		(at 133.731 -31.877 90)
		(property "Reference" "C137"
			(at 0 0 90)
			(layer "B.SilkS")
			(hide yes)
			(effects
				(font
					(size 1.27 1.27)
				)
				(justify mirror)
			)
		)
		(property "Value" "SC1U6D3V2KX-GP"
			(at -1.1811 -2.7051 90)
			(unlocked yes)
			(layer "B.Fab")
			(hide yes)
			(effects
				(font
					(size 1.016 1.016)
					(thickness 0.1524)
				)
				(justify mirror)
			)
		)
		(property "Device Type" "C402H22"
			(at -1.1811 -4.2291 90)
			(unlocked yes)
			(layer "B.Fab")
			(hide yes)
			(effects
				(font
					(size 1.016 1.016)
					(thickness 0.1524)
				)
				(justify mirror)
			)
		)
		(duplicate_pad_numbers_are_jumpers no)
		(fp_rect
			(start 0.381 0.7366)
			(end -0.381 -0.7366)
			(stroke
				(width 0)
				(type default)
			)
			(fill no)
			(layer "B.CrtYd")
		)
		(fp_rect
			(start 0.381 0.7366)
			(end -0.381 -0.7366)
			(stroke
				(width 0)
				(type default)
			)
			(fill no)
			(layer "B.Fab")
		)
		(pad "1" smd custom
			(at 0 -0.4572 270)
			(size 0.1143 0.1143)
			(layers "B.Cu" "B.Mask" "B.Paste")
			(net "GND")
			(options
				(clearance outline)
				(anchor circle)
			)
			(primitives
				(gr_poly
					(pts
						(arc
							(start -0.254 0.1778)
							(mid -0.239121 0.213721)
							(end -0.2032 0.2286)
						)
						(arc
							(start 0.2032 0.2286)
							(mid 0.239121 0.213721)
							(end 0.254 0.1778)
						)
						(arc
							(start 0.254 -0.1778)
							(mid 0.239121 -0.213721)
							(end 0.2032 -0.2286)
						)
						(arc
							(start -0.2032 -0.2286)
							(mid -0.239121 -0.213721)
							(end -0.254 -0.1778)
						)
					)
					(width 0)
					(fill yes)
				)
			)
		)
		(pad "2" smd custom
			(at 0 0.4572 270)
			(size 0.1143 0.1143)
			(layers "B.Cu" "B.Mask" "B.Paste")
			(net "P3V3_STBY")
			(options
				(clearance outline)
				(anchor circle)
			)
			(primitives
				(gr_poly
					(pts
						(arc
							(start -0.254 0.1778)
							(mid -0.239121 0.213721)
							(end -0.2032 0.2286)
						)
						(arc
							(start 0.2032 0.2286)
							(mid 0.239121 0.213721)
							(end 0.254 0.1778)
						)
						(arc
							(start 0.254 -0.1778)
							(mid 0.239121 -0.213721)
							(end 0.2032 -0.2286)
						)
						(arc
							(start -0.2032 -0.2286)
							(mid -0.239121 -0.213721)
							(end -0.254 -0.1778)
						)
					)
					(width 0)
					(fill yes)
				)
			)
		)
	)
	(footprint ""
		(layer "B.Cu")
		(at 15.494 -34.798 180)
		(property "Reference" "PR195"
			(at 0 0 0)
			(layer "B.SilkS")
			(hide yes)
			(effects
				(font
					(size 1.27 1.27)
				)
				(justify mirror)
			)
		)
		(property "Value" "15KR2F-GP"
			(at -1.7907 -1.1176 180)
			(unlocked yes)
			(layer "B.Fab")
			(hide yes)
			(effects
				(font
					(size 1.016 1.016)
					(thickness 0.1524)
				)
				(justify mirror)
			)
		)
		(property "Device Type" "R402H16"
			(at -1.7907 -2.6416 180)
			(unlocked yes)
			(layer "B.Fab")
			(hide yes)
			(effects
				(font
					(size 1.016 1.016)
					(thickness 0.1524)
				)
				(justify mirror)
			)
		)
		(duplicate_pad_numbers_are_jumpers no)
		(fp_rect
			(start 0.381 0.8382)
			(end -0.381 -0.8382)
			(stroke
				(width 0)
				(type default)
			)
			(fill no)
			(layer "B.CrtYd")
		)
		(fp_rect
			(start 0.381 0.8382)
			(end -0.381 -0.8382)
			(stroke
				(width 0)
				(type default)
			)
			(fill no)
			(layer "B.Fab")
		)
		(pad "1" smd custom
			(at 0 -0.4318)
			(size 0.127 0.127)
			(layers "B.Cu" "B.Mask" "B.Paste")
			(net "P3V3_STBY_PG")
			(options
				(clearance outline)
				(anchor circle)
			)
			(primitives
				(gr_poly
					(pts
						(arc
							(start -0.2032 0.2794)
							(mid -0.239121 0.264521)
							(end -0.254 0.2286)
						)
						(arc
							(start -0.254 -0.2286)
							(mid -0.239121 -0.264521)
							(end -0.2032 -0.2794)
						)
						(arc
							(start 0.2032 -0.2794)
							(mid 0.239121 -0.264521)
							(end 0.254 -0.2286)
						)
						(arc
							(start 0.254 0.2286)
							(mid 0.239121 0.264521)
							(end 0.2032 0.2794)
						)
					)
					(width 0)
					(fill yes)
				)
			)
		)
		(pad "2" smd custom
			(at 0 0.4318)
			(size 0.127 0.127)
			(layers "B.Cu" "B.Mask" "B.Paste")
			(net "GND")
			(options
				(clearance outline)
				(anchor circle)
			)
			(primitives
				(gr_poly
					(pts
						(arc
							(start -0.2032 0.2794)
							(mid -0.239121 0.264521)
							(end -0.254 0.2286)
						)
						(arc
							(start -0.254 -0.2286)
							(mid -0.239121 -0.264521)
							(end -0.2032 -0.2794)
						)
						(arc
							(start 0.2032 -0.2794)
							(mid 0.239121 -0.264521)
							(end 0.254 -0.2286)
						)
						(arc
							(start 0.254 0.2286)
							(mid 0.239121 0.264521)
							(end 0.2032 0.2794)
						)
					)
					(width 0)
					(fill yes)
				)
			)
		)
	)
	(footprint ""
		(layer "B.Cu")
		(at 89.662 -37.592 180)
		(property "Reference" "C190"
			(at 0 0 0)
			(layer "B.SilkS")
			(hide yes)
			(effects
				(font
					(size 1.27 1.27)
				)
				(justify mirror)
			)
		)
		(property "Value" "SC1U10V2KX-1GP"
			(at -1.1811 -2.7051 180)
			(unlocked yes)
			(layer "B.Fab")
			(hide yes)
			(effects
				(font
					(size 1.016 1.016)
					(thickness 0.1524)
				)
				(justify mirror)
			)
		)
		(property "Device Type" "C402H22"
			(at -1.1811 -4.2291 180)
			(unlocked yes)
			(layer "B.Fab")
			(hide yes)
			(effects
				(font
					(size 1.016 1.016)
					(thickness 0.1524)
				)
				(justify mirror)
			)
		)
		(duplicate_pad_numbers_are_jumpers no)
		(fp_rect
			(start 0.381 0.7366)
			(end -0.381 -0.7366)
			(stroke
				(width 0)
				(type default)
			)
			(fill no)
			(layer "B.CrtYd")
		)
		(fp_rect
			(start 0.381 0.7366)
			(end -0.381 -0.7366)
			(stroke
				(width 0)
				(type default)
			)
			(fill no)
			(layer "B.Fab")
		)
		(pad "1" smd custom
			(at 0 -0.4572)
			(size 0.1143 0.1143)
			(layers "B.Cu" "B.Mask" "B.Paste")
			(net "P3V3_CPU")
			(options
				(clearance outline)
				(anchor circle)
			)
			(primitives
				(gr_poly
					(pts
						(arc
							(start -0.254 0.1778)
							(mid -0.239121 0.213721)
							(end -0.2032 0.2286)
						)
						(arc
							(start 0.2032 0.2286)
							(mid 0.239121 0.213721)
							(end 0.254 0.1778)
						)
						(arc
							(start 0.254 -0.1778)
							(mid 0.239121 -0.213721)
							(end 0.2032 -0.2286)
						)
						(arc
							(start -0.2032 -0.2286)
							(mid -0.239121 -0.213721)
							(end -0.254 -0.1778)
						)
					)
					(width 0)
					(fill yes)
				)
			)
		)
		(pad "2" smd custom
			(at 0 0.4572)
			(size 0.1143 0.1143)
			(layers "B.Cu" "B.Mask" "B.Paste")
			(net "GND")
			(options
				(clearance outline)
				(anchor circle)
			)
			(primitives
				(gr_poly
					(pts
						(arc
							(start -0.254 0.1778)
							(mid -0.239121 0.213721)
							(end -0.2032 0.2286)
						)
						(arc
							(start 0.2032 0.2286)
							(mid 0.239121 0.213721)
							(end 0.254 0.1778)
						)
						(arc
							(start 0.254 -0.1778)
							(mid 0.239121 -0.213721)
							(end 0.2032 -0.2286)
						)
						(arc
							(start -0.2032 -0.2286)
							(mid -0.239121 -0.213721)
							(end -0.254 -0.1778)
						)
					)
					(width 0)
					(fill yes)
				)
			)
		)
	)
	(footprint ""
		(layer "B.Cu")
		(at 91.186 -44.577)
		(property "Reference" "C154"
			(at 0 0 0)
			(layer "B.SilkS")
			(hide yes)
			(effects
				(font
					(size 1.27 1.27)
				)
				(justify mirror)
			)
		)
		(property "Value" "SCD1U16V2JX-1-GP"
			(at -1.1811 -2.7051 0)
			(unlocked yes)
			(layer "B.Fab")
			(hide yes)
			(effects
				(font
					(size 1.016 1.016)
					(thickness 0.1524)
				)
				(justify mirror)
			)
		)
		(property "Device Type" "C402H22"
			(at -1.1811 -4.2291 0)
			(unlocked yes)
			(layer "B.Fab")
			(hide yes)
			(effects
				(font
					(size 1.016 1.016)
					(thickness 0.1524)
				)
				(justify mirror)
			)
		)
		(duplicate_pad_numbers_are_jumpers no)
		(fp_rect
			(start 0.381 0.7366)
			(end -0.381 -0.7366)
			(stroke
				(width 0)
				(type default)
			)
			(fill no)
			(layer "B.CrtYd")
		)
		(fp_rect
			(start 0.381 0.7366)
			(end -0.381 -0.7366)
			(stroke
				(width 0)
				(type default)
			)
			(fill no)
			(layer "B.Fab")
		)
		(pad "1" smd custom
			(at 0 -0.4572 180)
			(size 0.1143 0.1143)
			(layers "B.Cu" "B.Mask" "B.Paste")
			(net "P3V3_CPU")
			(options
				(clearance outline)
				(anchor circle)
			)
			(primitives
				(gr_poly
					(pts
						(arc
							(start -0.254 0.1778)
							(mid -0.239121 0.213721)
							(end -0.2032 0.2286)
						)
						(arc
							(start 0.2032 0.2286)
							(mid 0.239121 0.213721)
							(end 0.254 0.1778)
						)
						(arc
							(start 0.254 -0.1778)
							(mid 0.239121 -0.213721)
							(end 0.2032 -0.2286)
						)
						(arc
							(start -0.2032 -0.2286)
							(mid -0.239121 -0.213721)
							(end -0.254 -0.1778)
						)
					)
					(width 0)
					(fill yes)
				)
			)
		)
		(pad "2" smd custom
			(at 0 0.4572 180)
			(size 0.1143 0.1143)
			(layers "B.Cu" "B.Mask" "B.Paste")
			(net "GND")
			(options
				(clearance outline)
				(anchor circle)
			)
			(primitives
				(gr_poly
					(pts
						(arc
							(start -0.254 0.1778)
							(mid -0.239121 0.213721)
							(end -0.2032 0.2286)
						)
						(arc
							(start 0.2032 0.2286)
							(mid 0.239121 0.213721)
							(end 0.254 0.1778)
						)
						(arc
							(start 0.254 -0.1778)
							(mid 0.239121 -0.213721)
							(end 0.2032 -0.2286)
						)
						(arc
							(start -0.2032 -0.2286)
							(mid -0.239121 -0.213721)
							(end -0.254 -0.1778)
						)
					)
					(width 0)
					(fill yes)
				)
			)
		)
	)
	(footprint ""
		(layer "B.Cu")
		(at 110.617 -4.445 -90)
		(property "Reference" "C337"
			(at 0 0 90)
			(layer "B.SilkS")
			(hide yes)
			(effects
				(font
					(size 1.27 1.27)
				)
				(justify mirror)
			)
		)
		(property "Value" "SCD1U10V2KX-5GP"
			(at -1.8923 -1.2065 270)
			(unlocked yes)
			(layer "B.Fab")
			(hide yes)
			(effects
				(font
					(size 1.016 1.016)
					(thickness 0.1524)
				)
				(justify mirror)
			)
		)
		(property "Device Type" "C402H22"
			(at -1.8923 -2.7305 270)
			(unlocked yes)
			(layer "B.Fab")
			(hide yes)
			(effects
				(font
					(size 1.016 1.016)
					(thickness 0.1524)
				)
				(justify mirror)
			)
		)
		(duplicate_pad_numbers_are_jumpers no)
		(fp_rect
			(start 0.381 0.7366)
			(end -0.381 -0.7366)
			(stroke
				(width 0)
				(type default)
			)
			(fill no)
			(layer "B.CrtYd")
		)
		(fp_rect
			(start 0.381 0.7366)
			(end -0.381 -0.7366)
			(stroke
				(width 0)
				(type default)
			)
			(fill no)
			(layer "B.Fab")
		)
		(pad "1" smd custom
			(at 0 -0.4572 90)
			(size 0.1143 0.1143)
			(layers "B.Cu" "B.Mask" "B.Paste")
			(net "P3V3")
			(options
				(clearance outline)
				(anchor circle)
			)
			(primitives
				(gr_poly
					(pts
						(arc
							(start -0.254 0.1778)
							(mid -0.239121 0.213721)
							(end -0.2032 0.2286)
						)
						(arc
							(start 0.2032 0.2286)
							(mid 0.239121 0.213721)
							(end 0.254 0.1778)
						)
						(arc
							(start 0.254 -0.1778)
							(mid 0.239121 -0.213721)
							(end 0.2032 -0.2286)
						)
						(arc
							(start -0.2032 -0.2286)
							(mid -0.239121 -0.213721)
							(end -0.254 -0.1778)
						)
					)
					(width 0)
					(fill yes)
				)
			)
		)
		(pad "2" smd custom
			(at 0 0.4572 90)
			(size 0.1143 0.1143)
			(layers "B.Cu" "B.Mask" "B.Paste")
			(net "GND")
			(options
				(clearance outline)
				(anchor circle)
			)
			(primitives
				(gr_poly
					(pts
						(arc
							(start -0.254 0.1778)
							(mid -0.239121 0.213721)
							(end -0.2032 0.2286)
						)
						(arc
							(start 0.2032 0.2286)
							(mid 0.239121 0.213721)
							(end 0.254 0.1778)
						)
						(arc
							(start 0.254 -0.1778)
							(mid 0.239121 -0.213721)
							(end 0.2032 -0.2286)
						)
						(arc
							(start -0.2032 -0.2286)
							(mid -0.239121 -0.213721)
							(end -0.254 -0.1778)
						)
					)
					(width 0)
					(fill yes)
				)
			)
		)
	)
	(footprint ""
		(layer "B.Cu")
		(at 69.3928 -35.9156 -90)
		(property "Reference" "R405"
			(at 0 0 90)
			(layer "B.SilkS")
			(hide yes)
			(effects
				(font
					(size 1.27 1.27)
				)
				(justify mirror)
			)
		)
		(property "Value" "220KR2F-GP"
			(at -1.7907 -1.1176 270)
			(unlocked yes)
			(layer "B.Fab")
			(hide yes)
			(effects
				(font
					(size 1.016 1.016)
					(thickness 0.1524)
				)
				(justify mirror)
			)
		)
		(property "Device Type" "R402H16"
			(at -1.7907 -2.6416 270)
			(unlocked yes)
			(layer "B.Fab")
			(hide yes)
			(effects
				(font
					(size 1.016 1.016)
					(thickness 0.1524)
				)
				(justify mirror)
			)
		)
		(duplicate_pad_numbers_are_jumpers no)
		(fp_rect
			(start 0.381 0.8382)
			(end -0.381 -0.8382)
			(stroke
				(width 0)
				(type default)
			)
			(fill no)
			(layer "B.CrtYd")
		)
		(fp_rect
			(start 0.381 0.8382)
			(end -0.381 -0.8382)
			(stroke
				(width 0)
				(type default)
			)
			(fill no)
			(layer "B.Fab")
		)
		(pad "1" smd custom
			(at 0 -0.4318 90)
			(size 0.127 0.127)
			(layers "B.Cu" "B.Mask" "B.Paste")
			(net "SRTCRST_BUF_IN#")
			(options
				(clearance outline)
				(anchor circle)
			)
			(primitives
				(gr_poly
					(pts
						(arc
							(start -0.2032 0.2794)
							(mid -0.239121 0.264521)
							(end -0.254 0.2286)
						)
						(arc
							(start -0.254 -0.2286)
							(mid -0.239121 -0.264521)
							(end -0.2032 -0.2794)
						)
						(arc
							(start 0.2032 -0.2794)
							(mid 0.239121 -0.264521)
							(end 0.254 -0.2286)
						)
						(arc
							(start 0.254 0.2286)
							(mid 0.239121 0.264521)
							(end 0.2032 0.2794)
						)
					)
					(width 0)
					(fill yes)
				)
			)
		)
		(pad "2" smd custom
			(at 0 0.4318 90)
			(size 0.127 0.127)
			(layers "B.Cu" "B.Mask" "B.Paste")
			(net "GND")
			(options
				(clearance outline)
				(anchor circle)
			)
			(primitives
				(gr_poly
					(pts
						(arc
							(start -0.2032 0.2794)
							(mid -0.239121 0.264521)
							(end -0.254 0.2286)
						)
						(arc
							(start -0.254 -0.2286)
							(mid -0.239121 -0.264521)
							(end -0.2032 -0.2794)
						)
						(arc
							(start 0.2032 -0.2794)
							(mid 0.239121 -0.264521)
							(end 0.254 -0.2286)
						)
						(arc
							(start 0.254 0.2286)
							(mid 0.239121 0.264521)
							(end 0.2032 0.2794)
						)
					)
					(width 0)
					(fill yes)
				)
			)
		)
	)
	(footprint ""
		(layer "B.Cu")
		(at 112.268 -9.144 -90)
		(property "Reference" "R478"
			(at 0 0 90)
			(layer "B.SilkS")
			(hide yes)
			(effects
				(font
					(size 1.27 1.27)
				)
				(justify mirror)
			)
		)
		(property "Value" "10KR2F-2-GP"
			(at -1.7907 -1.1176 270)
			(unlocked yes)
			(layer "B.Fab")
			(hide yes)
			(effects
				(font
					(size 1.016 1.016)
					(thickness 0.1524)
				)
				(justify mirror)
			)
		)
		(property "Device Type" "R402H16"
			(at -1.7907 -2.6416 270)
			(unlocked yes)
			(layer "B.Fab")
			(hide yes)
			(effects
				(font
					(size 1.016 1.016)
					(thickness 0.1524)
				)
				(justify mirror)
			)
		)
		(duplicate_pad_numbers_are_jumpers no)
		(fp_rect
			(start 0.381 0.8382)
			(end -0.381 -0.8382)
			(stroke
				(width 0)
				(type default)
			)
			(fill no)
			(layer "B.CrtYd")
		)
		(fp_rect
			(start 0.381 0.8382)
			(end -0.381 -0.8382)
			(stroke
				(width 0)
				(type default)
			)
			(fill no)
			(layer "B.Fab")
		)
		(pad "1" smd custom
			(at 0 -0.4318 90)
			(size 0.127 0.127)
			(layers "B.Cu" "B.Mask" "B.Paste")
			(net "P3V3")
			(options
				(clearance outline)
				(anchor circle)
			)
			(primitives
				(gr_poly
					(pts
						(arc
							(start -0.2032 0.2794)
							(mid -0.239121 0.264521)
							(end -0.254 0.2286)
						)
						(arc
							(start -0.254 -0.2286)
							(mid -0.239121 -0.264521)
							(end -0.2032 -0.2794)
						)
						(arc
							(start 0.2032 -0.2794)
							(mid 0.239121 -0.264521)
							(end 0.254 -0.2286)
						)
						(arc
							(start 0.254 0.2286)
							(mid 0.239121 0.264521)
							(end 0.2032 0.2794)
						)
					)
					(width 0)
					(fill yes)
				)
			)
		)
		(pad "2" smd custom
			(at 0 0.4318 90)
			(size 0.127 0.127)
			(layers "B.Cu" "B.Mask" "B.Paste")
			(net "IRQ_MCERR#")
			(options
				(clearance outline)
				(anchor circle)
			)
			(primitives
				(gr_poly
					(pts
						(arc
							(start -0.2032 0.2794)
							(mid -0.239121 0.264521)
							(end -0.254 0.2286)
						)
						(arc
							(start -0.254 -0.2286)
							(mid -0.239121 -0.264521)
							(end -0.2032 -0.2794)
						)
						(arc
							(start 0.2032 -0.2794)
							(mid 0.239121 -0.264521)
							(end 0.254 -0.2286)
						)
						(arc
							(start 0.254 0.2286)
							(mid 0.239121 0.264521)
							(end 0.2032 0.2794)
						)
					)
					(width 0)
					(fill yes)
				)
			)
		)
	)
	(footprint ""
		(layer "B.Cu")
		(at 100.33 -63.881 180)
		(property "Reference" "PR4"
			(at 0 0 0)
			(layer "B.SilkS")
			(hide yes)
			(effects
				(font
					(size 1.27 1.27)
				)
				(justify mirror)
			)
		)
		(property "Value" "0R2J-2-GP"
			(at -0.064008 -3.993896 180)
			(unlocked yes)
			(layer "B.Fab")
			(hide yes)
			(effects
				(font
					(size 1.016 1.016)
					(thickness 0.1524)
				)
				(justify mirror)
			)
		)
		(property "Device Type" "R402H16"
			(at -0.064008 -5.517896 180)
			(unlocked yes)
			(layer "B.Fab")
			(hide yes)
			(effects
				(font
					(size 1.016 1.016)
					(thickness 0.1524)
				)
				(justify mirror)
			)
		)
		(duplicate_pad_numbers_are_jumpers no)
		(fp_rect
			(start 0.381 0.8382)
			(end -0.381 -0.8382)
			(stroke
				(width 0)
				(type default)
			)
			(fill no)
			(layer "B.CrtYd")
		)
		(fp_rect
			(start 0.381 0.8382)
			(end -0.381 -0.8382)
			(stroke
				(width 0)
				(type default)
			)
			(fill no)
			(layer "B.Fab")
		)
		(pad "1" smd custom
			(at 0 -0.4318)
			(size 0.127 0.127)
			(layers "B.Cu" "B.Mask" "B.Paste")
			(net "P3V3_STBY")
			(options
				(clearance outline)
				(anchor circle)
			)
			(primitives
				(gr_poly
					(pts
						(arc
							(start -0.2032 0.2794)
							(mid -0.239121 0.264521)
							(end -0.254 0.2286)
						)
						(arc
							(start -0.254 -0.2286)
							(mid -0.239121 -0.264521)
							(end -0.2032 -0.2794)
						)
						(arc
							(start 0.2032 -0.2794)
							(mid 0.239121 -0.264521)
							(end 0.254 -0.2286)
						)
						(arc
							(start 0.254 0.2286)
							(mid 0.239121 0.264521)
							(end 0.2032 0.2794)
						)
					)
					(width 0)
					(fill yes)
				)
			)
		)
		(pad "2" smd custom
			(at 0 0.4318)
			(size 0.127 0.127)
			(layers "B.Cu" "B.Mask" "B.Paste")
			(net "VR_P1V1_AVIN")
			(options
				(clearance outline)
				(anchor circle)
			)
			(primitives
				(gr_poly
					(pts
						(arc
							(start -0.2032 0.2794)
							(mid -0.239121 0.264521)
							(end -0.254 0.2286)
						)
						(arc
							(start -0.254 -0.2286)
							(mid -0.239121 -0.264521)
							(end -0.2032 -0.2794)
						)
						(arc
							(start 0.2032 -0.2794)
							(mid 0.239121 -0.264521)
							(end 0.254 -0.2286)
						)
						(arc
							(start 0.254 0.2286)
							(mid 0.239121 0.264521)
							(end 0.2032 0.2794)
						)
					)
					(width 0)
					(fill yes)
				)
			)
		)
	)
)
